(kicad_pcb
	(version 20260206)
	(generator "pcbnew")
	(generator_version "10.0")
	(general
		(thickness 1.6)
		(legacy_teardrops no)
	)
	(paper "A4")
	(title_block
		(title "03242023_DA0F0TMBIJ0_F0T_Motherboard_J_brd_V01_OCP.brd")
		(comment 1 "Grand Teton / footprints 3054-3059 of 6105")
	)
	(layers
		(0 "F.Cu" signal "TOP")
		(4 "In1.Cu" signal "GND")
		(6 "In2.Cu" signal "IN1")
		(8 "In3.Cu" signal "GND1")
		(10 "In4.Cu" signal "IN2")
		(12 "In5.Cu" signal "GND2")
		(14 "In6.Cu" signal "IN3")
		(16 "In7.Cu" signal "GND3")
		(18 "In8.Cu" signal "VCC")
		(20 "In9.Cu" signal "VCC1")
		(22 "In10.Cu" signal "GND4")
		(24 "In11.Cu" signal "IN4")
		(26 "In12.Cu" signal "GND5")
		(28 "In13.Cu" signal "IN5")
		(30 "In14.Cu" signal "GND6")
		(32 "In15.Cu" signal "IN6")
		(34 "In16.Cu" signal "GND7")
		(2 "B.Cu" signal "BOTTOM")
		(9 "F.Adhes" user "F.Adhesive")
		(11 "B.Adhes" user "B.Adhesive")
		(13 "F.Paste" user "Package Geometry/Pastemask Top")
		(15 "B.Paste" user "Package Geometry/Pastemask Bottom")
		(5 "F.SilkS" user "Ref Des/Silkscreen Top")
		(7 "B.SilkS" user "Ref Des/Silkscreen Bottom")
		(1 "F.Mask" user "Board Geometry/Soldermask Top")
		(3 "B.Mask" user "Board Geometry/Soldermask Bottom")
		(17 "Dwgs.User" user "User.Drawings")
		(19 "Cmts.User" user "User.Comments")
		(21 "Eco1.User" user "User.Eco1")
		(23 "Eco2.User" user "User.Eco2")
		(25 "Edge.Cuts" user "Board Geometry/Outline")
		(27 "Margin" user)
		(31 "F.CrtYd" user "Package Geometry/Place Bound Top")
		(29 "B.CrtYd" user "Package Geometry/Place Bound Bottom")
		(35 "F.Fab" user "Ref Des/Assembly Top")
		(33 "B.Fab" user "Ref Des/Assembly Bottom")
	)
	(footprint ""
		(layer "F.Cu")
		(at 357.587042 -393.28725 180)
		(property "Reference" "R4161"
			(at 0 0 180)
			(layer "F.SilkS")
			(hide yes)
			(effects
				(font
					(size 1.27 1.27)
				)
			)
		)
		(property "Value" ""
			(at 0 0 180)
			(layer "F.Fab")
			(effects
				(font
					(size 1.27 1.27)
				)
			)
		)
		(duplicate_pad_numbers_are_jumpers no)
		(fp_line
			(start 0.7874 0.4064)
			(end -0.7874 0.4064)
			(stroke
				(width 0.1524)
				(type default)
			)
			(layer "F.SilkS")
		)
		(fp_line
			(start 0.7874 -0.4064)
			(end 0.7874 0.4064)
			(stroke
				(width 0.1524)
				(type default)
			)
			(layer "F.SilkS")
		)
		(fp_line
			(start -0.7874 0.4064)
			(end -0.7874 -0.4064)
			(stroke
				(width 0.1524)
				(type default)
			)
			(layer "F.SilkS")
		)
		(fp_line
			(start -0.7874 -0.4064)
			(end 0.7874 -0.4064)
			(stroke
				(width 0.1524)
				(type default)
			)
			(layer "F.SilkS")
		)
		(fp_line
			(start 0.67945 0.3048)
			(end 0.120396 0.3048)
			(stroke
				(width 0.1)
				(type default)
			)
			(layer "F.Fab")
		)
		(fp_line
			(start 0.67945 -0.3048)
			(end 0.67945 0.3048)
			(stroke
				(width 0.1)
				(type default)
			)
			(layer "F.Fab")
		)
		(fp_line
			(start 0.12065 -0.2794)
			(end 0.12065 -0.3048)
			(stroke
				(width 0.1)
				(type default)
			)
			(layer "F.Fab")
		)
		(fp_line
			(start 0.12065 -0.3048)
			(end 0.67945 -0.3048)
			(stroke
				(width 0.1)
				(type default)
			)
			(layer "F.Fab")
		)
		(fp_line
			(start 0.120396 0.3048)
			(end 0.120396 0.2794)
			(stroke
				(width 0.1)
				(type default)
			)
			(layer "F.Fab")
		)
		(fp_line
			(start 0.120396 0.2794)
			(end -0.12065 0.2794)
			(stroke
				(width 0.1)
				(type default)
			)
			(layer "F.Fab")
		)
		(fp_line
			(start -0.12065 0.3048)
			(end -0.67945 0.3048)
			(stroke
				(width 0.1)
				(type default)
			)
			(layer "F.Fab")
		)
		(fp_line
			(start -0.12065 0.2794)
			(end -0.12065 0.3048)
			(stroke
				(width 0.1)
				(type default)
			)
			(layer "F.Fab")
		)
		(fp_line
			(start -0.12065 -0.2794)
			(end 0.12065 -0.2794)
			(stroke
				(width 0.1)
				(type default)
			)
			(layer "F.Fab")
		)
		(fp_line
			(start -0.12065 -0.305054)
			(end -0.12065 -0.2794)
			(stroke
				(width 0.1)
				(type default)
			)
			(layer "F.Fab")
		)
		(fp_line
			(start -0.67945 0.3048)
			(end -0.67945 -0.305054)
			(stroke
				(width 0.1)
				(type default)
			)
			(layer "F.Fab")
		)
		(fp_line
			(start -0.67945 -0.305054)
			(end -0.12065 -0.305054)
			(stroke
				(width 0.1)
				(type default)
			)
			(layer "F.Fab")
		)
		(pad "1" smd circle
			(at -0.40005 0 180)
			(size 0 0)
			(layers "F.Cu" "F.Mask" "F.Paste")
			(net "GPU_3V3IO_RSVD4")
		)
		(pad "2" smd circle
			(at 0.40005 0 180)
			(size 0 0)
			(layers "F.Cu" "F.Mask" "F.Paste")
			(net "GND")
		)
	)
	(footprint ""
		(layer "F.Cu")
		(at 337.845908 -16.219678 -90)
		(property "Reference" "C605"
			(at 0 0 270)
			(layer "F.SilkS")
			(hide yes)
			(effects
				(font
					(size 1.27 1.27)
				)
			)
		)
		(property "Value" ""
			(at 0 0 270)
			(layer "F.Fab")
			(effects
				(font
					(size 1.27 1.27)
				)
			)
		)
		(duplicate_pad_numbers_are_jumpers no)
		(fp_line
			(start -0.7874 0.4064)
			(end -0.7874 -0.4064)
			(stroke
				(width 0.1524)
				(type default)
			)
			(layer "F.SilkS")
		)
		(fp_line
			(start 0.7874 0.4064)
			(end -0.7874 0.4064)
			(stroke
				(width 0.1524)
				(type default)
			)
			(layer "F.SilkS")
		)
		(fp_line
			(start -0.7874 -0.4064)
			(end 0.7874 -0.4064)
			(stroke
				(width 0.1524)
				(type default)
			)
			(layer "F.SilkS")
		)
		(fp_line
			(start 0.7874 -0.4064)
			(end 0.7874 0.4064)
			(stroke
				(width 0.1524)
				(type default)
			)
			(layer "F.SilkS")
		)
		(fp_line
			(start -0.67945 0.3048)
			(end -0.67945 -0.305054)
			(stroke
				(width 0.1)
				(type default)
			)
			(layer "F.Fab")
		)
		(fp_line
			(start -0.12065 0.3048)
			(end -0.67945 0.3048)
			(stroke
				(width 0.1)
				(type default)
			)
			(layer "F.Fab")
		)
		(fp_line
			(start 0.120396 0.3048)
			(end 0.120396 0.2794)
			(stroke
				(width 0.1)
				(type default)
			)
			(layer "F.Fab")
		)
		(fp_line
			(start 0.67945 0.3048)
			(end 0.120396 0.3048)
			(stroke
				(width 0.1)
				(type default)
			)
			(layer "F.Fab")
		)
		(fp_line
			(start -0.12065 0.2794)
			(end -0.12065 0.3048)
			(stroke
				(width 0.1)
				(type default)
			)
			(layer "F.Fab")
		)
		(fp_line
			(start 0.120396 0.2794)
			(end -0.12065 0.2794)
			(stroke
				(width 0.1)
				(type default)
			)
			(layer "F.Fab")
		)
		(fp_line
			(start -0.12065 -0.2794)
			(end 0.12065 -0.2794)
			(stroke
				(width 0.1)
				(type default)
			)
			(layer "F.Fab")
		)
		(fp_line
			(start 0.12065 -0.2794)
			(end 0.12065 -0.3048)
			(stroke
				(width 0.1)
				(type default)
			)
			(layer "F.Fab")
		)
		(fp_line
			(start 0.12065 -0.3048)
			(end 0.67945 -0.3048)
			(stroke
				(width 0.1)
				(type default)
			)
			(layer "F.Fab")
		)
		(fp_line
			(start 0.67945 -0.3048)
			(end 0.67945 0.3048)
			(stroke
				(width 0.1)
				(type default)
			)
			(layer "F.Fab")
		)
		(fp_line
			(start -0.67945 -0.305054)
			(end -0.12065 -0.305054)
			(stroke
				(width 0.1)
				(type default)
			)
			(layer "F.Fab")
		)
		(fp_line
			(start -0.12065 -0.305054)
			(end -0.12065 -0.2794)
			(stroke
				(width 0.1)
				(type default)
			)
			(layer "F.Fab")
		)
		(pad "1" smd circle
			(at -0.40005 0 270)
			(size 0 0)
			(layers "F.Cu" "F.Mask" "F.Paste")
			(net "PGPPA_AUX")
		)
		(pad "2" smd circle
			(at 0.40005 0 270)
			(size 0 0)
			(layers "F.Cu" "F.Mask" "F.Paste")
			(net "GND")
		)
	)
	(footprint ""
		(layer "F.Cu")
		(at 355.229414 -251.375418 90)
		(property "Reference" "C1026"
			(at 0 0 90)
			(layer "F.SilkS")
			(hide yes)
			(effects
				(font
					(size 1.27 1.27)
				)
			)
		)
		(property "Value" ""
			(at 0 0 90)
			(layer "F.Fab")
			(effects
				(font
					(size 1.27 1.27)
				)
			)
		)
		(duplicate_pad_numbers_are_jumpers no)
		(fp_line
			(start 0.7874 -0.4064)
			(end 0.7874 0.4064)
			(stroke
				(width 0.1524)
				(type default)
			)
			(layer "F.SilkS")
		)
		(fp_line
			(start -0.7874 -0.4064)
			(end 0.7874 -0.4064)
			(stroke
				(width 0.1524)
				(type default)
			)
			(layer "F.SilkS")
		)
		(fp_line
			(start 0.7874 0.4064)
			(end -0.7874 0.4064)
			(stroke
				(width 0.1524)
				(type default)
			)
			(layer "F.SilkS")
		)
		(fp_line
			(start -0.7874 0.4064)
			(end -0.7874 -0.4064)
			(stroke
				(width 0.1524)
				(type default)
			)
			(layer "F.SilkS")
		)
		(fp_line
			(start -0.12065 -0.305054)
			(end -0.12065 -0.2794)
			(stroke
				(width 0.1)
				(type default)
			)
			(layer "F.Fab")
		)
		(fp_line
			(start -0.67945 -0.305054)
			(end -0.12065 -0.305054)
			(stroke
				(width 0.1)
				(type default)
			)
			(layer "F.Fab")
		)
		(fp_line
			(start 0.67945 -0.3048)
			(end 0.67945 0.3048)
			(stroke
				(width 0.1)
				(type default)
			)
			(layer "F.Fab")
		)
		(fp_line
			(start 0.12065 -0.3048)
			(end 0.67945 -0.3048)
			(stroke
				(width 0.1)
				(type default)
			)
			(layer "F.Fab")
		)
		(fp_line
			(start 0.12065 -0.2794)
			(end 0.12065 -0.3048)
			(stroke
				(width 0.1)
				(type default)
			)
			(layer "F.Fab")
		)
		(fp_line
			(start -0.12065 -0.2794)
			(end 0.12065 -0.2794)
			(stroke
				(width 0.1)
				(type default)
			)
			(layer "F.Fab")
		)
		(fp_line
			(start 0.120396 0.2794)
			(end -0.12065 0.2794)
			(stroke
				(width 0.1)
				(type default)
			)
			(layer "F.Fab")
		)
		(fp_line
			(start -0.12065 0.2794)
			(end -0.12065 0.3048)
			(stroke
				(width 0.1)
				(type default)
			)
			(layer "F.Fab")
		)
		(fp_line
			(start 0.67945 0.3048)
			(end 0.120396 0.3048)
			(stroke
				(width 0.1)
				(type default)
			)
			(layer "F.Fab")
		)
		(fp_line
			(start 0.120396 0.3048)
			(end 0.120396 0.2794)
			(stroke
				(width 0.1)
				(type default)
			)
			(layer "F.Fab")
		)
		(fp_line
			(start -0.12065 0.3048)
			(end -0.67945 0.3048)
			(stroke
				(width 0.1)
				(type default)
			)
			(layer "F.Fab")
		)
		(fp_line
			(start -0.67945 0.3048)
			(end -0.67945 -0.305054)
			(stroke
				(width 0.1)
				(type default)
			)
			(layer "F.Fab")
		)
		(pad "1" smd circle
			(at -0.40005 0 90)
			(size 0 0)
			(layers "F.Cu" "F.Mask" "F.Paste")
			(net "PVCCIN_CPU0")
		)
		(pad "2" smd circle
			(at 0.40005 0 90)
			(size 0 0)
			(layers "F.Cu" "F.Mask" "F.Paste")
			(net "GND")
		)
	)
	(footprint ""
		(layer "F.Cu")
		(at 126.89078 -108.295948 -90)
		(property "Reference" "C2247"
			(at 0 0 270)
			(layer "F.SilkS")
			(hide yes)
			(effects
				(font
					(size 1.27 1.27)
				)
			)
		)
		(property "Value" ""
			(at 0 0 270)
			(layer "F.Fab")
			(effects
				(font
					(size 1.27 1.27)
				)
			)
		)
		(duplicate_pad_numbers_are_jumpers no)
		(fp_line
			(start -0.7874 0.4064)
			(end -0.7874 -0.4064)
			(stroke
				(width 0.1524)
				(type default)
			)
			(layer "F.SilkS")
		)
		(fp_line
			(start 0.7874 0.4064)
			(end -0.7874 0.4064)
			(stroke
				(width 0.1524)
				(type default)
			)
			(layer "F.SilkS")
		)
		(fp_line
			(start -0.7874 -0.4064)
			(end 0.7874 -0.4064)
			(stroke
				(width 0.1524)
				(type default)
			)
			(layer "F.SilkS")
		)
		(fp_line
			(start 0.7874 -0.4064)
			(end 0.7874 0.4064)
			(stroke
				(width 0.1524)
				(type default)
			)
			(layer "F.SilkS")
		)
		(fp_line
			(start -0.67945 0.3048)
			(end -0.67945 -0.305054)
			(stroke
				(width 0.1)
				(type default)
			)
			(layer "F.Fab")
		)
		(fp_line
			(start -0.12065 0.3048)
			(end -0.67945 0.3048)
			(stroke
				(width 0.1)
				(type default)
			)
			(layer "F.Fab")
		)
		(fp_line
			(start 0.120396 0.3048)
			(end 0.120396 0.2794)
			(stroke
				(width 0.1)
				(type default)
			)
			(layer "F.Fab")
		)
		(fp_line
			(start 0.67945 0.3048)
			(end 0.120396 0.3048)
			(stroke
				(width 0.1)
				(type default)
			)
			(layer "F.Fab")
		)
		(fp_line
			(start -0.12065 0.2794)
			(end -0.12065 0.3048)
			(stroke
				(width 0.1)
				(type default)
			)
			(layer "F.Fab")
		)
		(fp_line
			(start 0.120396 0.2794)
			(end -0.12065 0.2794)
			(stroke
				(width 0.1)
				(type default)
			)
			(layer "F.Fab")
		)
		(fp_line
			(start -0.12065 -0.2794)
			(end 0.12065 -0.2794)
			(stroke
				(width 0.1)
				(type default)
			)
			(layer "F.Fab")
		)
		(fp_line
			(start 0.12065 -0.2794)
			(end 0.12065 -0.3048)
			(stroke
				(width 0.1)
				(type default)
			)
			(layer "F.Fab")
		)
		(fp_line
			(start 0.12065 -0.3048)
			(end 0.67945 -0.3048)
			(stroke
				(width 0.1)
				(type default)
			)
			(layer "F.Fab")
		)
		(fp_line
			(start 0.67945 -0.3048)
			(end 0.67945 0.3048)
			(stroke
				(width 0.1)
				(type default)
			)
			(layer "F.Fab")
		)
		(fp_line
			(start -0.67945 -0.305054)
			(end -0.12065 -0.305054)
			(stroke
				(width 0.1)
				(type default)
			)
			(layer "F.Fab")
		)
		(fp_line
			(start -0.12065 -0.305054)
			(end -0.12065 -0.2794)
			(stroke
				(width 0.1)
				(type default)
			)
			(layer "F.Fab")
		)
		(pad "1" smd circle
			(at -0.40005 0 270)
			(size 0 0)
			(layers "F.Cu" "F.Mask" "F.Paste")
			(net "P3V3_AUX")
		)
		(pad "2" smd circle
			(at 0.40005 0 270)
			(size 0 0)
			(layers "F.Cu" "F.Mask" "F.Paste")
			(net "GND")
		)
	)
	(footprint ""
		(layer "F.Cu")
		(at 18.753582 -428.049436 90)
		(property "Reference" "R3442"
			(at 0 0 90)
			(layer "F.SilkS")
			(hide yes)
			(effects
				(font
					(size 1.27 1.27)
				)
			)
		)
		(property "Value" ""
			(at 0 0 90)
			(layer "F.Fab")
			(effects
				(font
					(size 1.27 1.27)
				)
			)
		)
		(duplicate_pad_numbers_are_jumpers no)
		(fp_line
			(start 0.7874 -0.4064)
			(end 0.7874 0.4064)
			(stroke
				(width 0.1524)
				(type default)
			)
			(layer "F.SilkS")
		)
		(fp_line
			(start -0.7874 -0.4064)
			(end 0.7874 -0.4064)
			(stroke
				(width 0.1524)
				(type default)
			)
			(layer "F.SilkS")
		)
		(fp_line
			(start 0.7874 0.4064)
			(end -0.7874 0.4064)
			(stroke
				(width 0.1524)
				(type default)
			)
			(layer "F.SilkS")
		)
		(fp_line
			(start -0.7874 0.4064)
			(end -0.7874 -0.4064)
			(stroke
				(width 0.1524)
				(type default)
			)
			(layer "F.SilkS")
		)
		(fp_line
			(start -0.12065 -0.305054)
			(end -0.12065 -0.2794)
			(stroke
				(width 0.1)
				(type default)
			)
			(layer "F.Fab")
		)
		(fp_line
			(start -0.67945 -0.305054)
			(end -0.12065 -0.305054)
			(stroke
				(width 0.1)
				(type default)
			)
			(layer "F.Fab")
		)
		(fp_line
			(start 0.67945 -0.3048)
			(end 0.67945 0.3048)
			(stroke
				(width 0.1)
				(type default)
			)
			(layer "F.Fab")
		)
		(fp_line
			(start 0.12065 -0.3048)
			(end 0.67945 -0.3048)
			(stroke
				(width 0.1)
				(type default)
			)
			(layer "F.Fab")
		)
		(fp_line
			(start 0.12065 -0.2794)
			(end 0.12065 -0.3048)
			(stroke
				(width 0.1)
				(type default)
			)
			(layer "F.Fab")
		)
		(fp_line
			(start -0.12065 -0.2794)
			(end 0.12065 -0.2794)
			(stroke
				(width 0.1)
				(type default)
			)
			(layer "F.Fab")
		)
		(fp_line
			(start 0.120396 0.2794)
			(end -0.12065 0.2794)
			(stroke
				(width 0.1)
				(type default)
			)
			(layer "F.Fab")
		)
		(fp_line
			(start -0.12065 0.2794)
			(end -0.12065 0.3048)
			(stroke
				(width 0.1)
				(type default)
			)
			(layer "F.Fab")
		)
		(fp_line
			(start 0.67945 0.3048)
			(end 0.120396 0.3048)
			(stroke
				(width 0.1)
				(type default)
			)
			(layer "F.Fab")
		)
		(fp_line
			(start 0.120396 0.3048)
			(end 0.120396 0.2794)
			(stroke
				(width 0.1)
				(type default)
			)
			(layer "F.Fab")
		)
		(fp_line
			(start -0.12065 0.3048)
			(end -0.67945 0.3048)
			(stroke
				(width 0.1)
				(type default)
			)
			(layer "F.Fab")
		)
		(fp_line
			(start -0.67945 0.3048)
			(end -0.67945 -0.305054)
			(stroke
				(width 0.1)
				(type default)
			)
			(layer "F.Fab")
		)
		(pad "1" smd circle
			(at -0.40005 0 90)
			(size 0 0)
			(layers "F.Cu" "F.Mask" "F.Paste")
			(net "GPU_PEX_STRAP0")
		)
		(pad "2" smd circle
			(at 0.40005 0 90)
			(size 0 0)
			(layers "F.Cu" "F.Mask" "F.Paste")
			(net "GND")
		)
	)
	(footprint ""
		(layer "F.Cu")
		(at 183.66486 -422.58742 90)
		(property "Reference" "U343"
			(at -2.11074 2.34569 90)
			(unlocked yes)
			(layer "F.SilkS")
			(effects
				(font
					(size 0.7874 0.5842)
					(thickness 0.1524)
				)
				(justify left)
			)
		)
		(property "Value" ""
			(at 0 0 90)
			(layer "F.Fab")
			(effects
				(font
					(size 1.27 1.27)
				)
			)
		)
		(duplicate_pad_numbers_are_jumpers no)
		(fp_line
			(start 1.868424 -1.519936)
			(end -1.868424 -1.519936)
			(stroke
				(width 0.1524)
				(type default)
			)
			(layer "F.SilkS")
		)
		(fp_line
			(start -1.868424 -1.519936)
			(end -1.868424 1.519936)
			(stroke
				(width 0.1524)
				(type default)
			)
			(layer "F.SilkS")
		)
		(fp_line
			(start 1.868424 1.519936)
			(end 1.868424 -1.519936)
			(stroke
				(width 0.1524)
				(type default)
			)
			(layer "F.SilkS")
		)
		(fp_line
			(start -1.868424 1.519936)
			(end 1.868424 1.519936)
			(stroke
				(width 0.1524)
				(type default)
			)
			(layer "F.SilkS")
		)
		(fp_line
			(start 0.700024 -1.519936)
			(end -0.700024 -1.519936)
			(stroke
				(width 0.1)
				(type default)
			)
			(layer "F.Fab")
		)
		(fp_line
			(start -0.700024 -1.519936)
			(end -0.700024 1.519936)
			(stroke
				(width 0.1)
				(type default)
			)
			(layer "F.Fab")
		)
		(fp_line
			(start 0.700024 1.519936)
			(end 0.700024 -1.519936)
			(stroke
				(width 0.1)
				(type default)
			)
			(layer "F.Fab")
		)
		(fp_line
			(start -0.700024 1.519936)
			(end 0.700024 1.519936)
			(stroke
				(width 0.1)
				(type default)
			)
			(layer "F.Fab")
		)
		(pad "1" smd rect
			(at -1.18491 -0.94996)
			(size 0.6096 1.0668)
			(layers "F.Cu" "F.Mask" "F.Paste")
			(net "OC_P2V5_COMP")
		)
		(pad "2" smd rect
			(at -1.18491 0.94996)
			(size 0.6096 1.0668)
			(layers "F.Cu" "F.Mask" "F.Paste")
			(net "GND")
		)
		(pad "3" smd rect
			(at 1.18491 0)
			(size 0.6096 1.0668)
			(layers "F.Cu" "F.Mask" "F.Paste")
			(net "Net_8629")
		)
	)
)
